(kicad_pcb
	(version 20211014)
	(generator pcbnew)
	(general
    (thickness 1.6)
  )
	(paper "A4")
	(title_block
    (title "SA800U (Snapdragon 845) Baseboard")
    (date "2023-10-19")
    (rev "1.0.3")
    (company "Antmicro Ltd.")
    (comment 1 "www.antmicro.com")
		(comment 9 "footprints 363-372 of 589")
	)
	(layers
    (0 "F.Cu" signal)
    (1 "In1.Cu" power)
    (2 "In2.Cu" signal)
    (3 "In3.Cu" signal)
    (4 "In4.Cu" power)
    (31 "B.Cu" signal)
    (32 "B.Adhes" user "B.Adhesive")
    (33 "F.Adhes" user "F.Adhesive")
    (34 "B.Paste" user)
    (35 "F.Paste" user)
    (36 "B.SilkS" user "B.Silkscreen")
    (37 "F.SilkS" user "F.Silkscreen")
    (38 "B.Mask" user)
    (39 "F.Mask" user)
    (40 "Dwgs.User" user "User.Drawings")
    (41 "Cmts.User" user "User.Comments")
    (42 "Eco1.User" user "User.Eco1")
    (43 "Eco2.User" user "User.Eco2")
    (44 "Edge.Cuts" user)
    (45 "Margin" user)
    (46 "B.CrtYd" user "B.Courtyard")
    (47 "F.CrtYd" user "F.Courtyard")
    (48 "B.Fab" user)
    (49 "F.Fab" user)
  )
	(footprint "sa800u-baseboard-hw-footprints:R_0402_1005Metric" (layer "B.Cu")
    (tedit 5FD9C158)
    (at 101.549174 103.257734 180)
    (descr "Resistor SMD 0402")
    (tags "resistor SMD 0402")
    (property "Author" "Antmicro")
    (property "License" "Apache-2.0")
    (property "MPN" "CR0402-FX-1001GLF")
    (property "Manufacturer" "Bourns")
    (property "Sheetfile" "ethernet-controller.kicad_sch")
    (property "Sheetname" "Ethernet Controller")
    (property "Tolerance" "1%")
    (property "Val" "1k")
    (attr smd)
    (fp_text reference "R7" (at -2.420827 -0.272266) (layer "B.SilkS")
      (effects (font (size 0.7 0.7) (thickness 0.15)) (justify left bottom mirror))
    )
    (fp_text value "R_1k_0402" (at 0 -1.4) (layer "B.Fab")
      (effects (font (size 0.7 0.7) (thickness 0.15)) (justify left bottom mirror))
    )
    (fp_text user "License: Apache-2.0" (at -0.95 -5.169) (layer "B.Fab") hide
      (effects (font (size 0.7 0.7) (thickness 0.15)) (justify left bottom mirror))
    )
    (fp_text user "${REFERENCE}" (at -0.95 -3.168) (layer "B.Fab") hide
      (effects (font (size 0.7 0.7) (thickness 0.15)) (justify left bottom mirror))
    )
    (fp_text user "Author: Antmicro" (at -0.95 -4.169) (layer "B.Fab") hide
      (effects (font (size 0.7 0.7) (thickness 0.15)) (justify left bottom mirror))
    )
    (fp_rect (start -0.93 0.47) (end 0.93 -0.47) (layer "B.CrtYd") (width 0.05) (fill none))
    (fp_rect (start -0.5 0.25) (end 0.5 -0.25) (layer "B.Fab") (width 0.15) (fill none))
    (pad "1" smd roundrect (at -0.485 0 180) (size 0.59 0.64) (layers "B.Cu" "B.Paste" "B.Mask") (roundrect_rratio 0.25)
      (net 132 "VREG_S4A_1V8") (pintype "passive"))
    (pad "2" smd roundrect (at 0.485 0 180) (size 0.59 0.64) (layers "B.Cu" "B.Paste" "B.Mask") (roundrect_rratio 0.25)
      (net 161 "PCIE1_WAKE_N") (pintype "passive"))
  )
	(footprint "sa800u-baseboard-hw-footprints:C_0402_1005Metric" (layer "B.Cu")
    (tedit 616D63CF)
    (at 99.549174 106.357734 -90)
    (descr "Capacitor SMD 0402")
    (tags "capacitor SMD 0402")
    (property "Author" "Antmicro")
    (property "Dielectric" "X5R")
    (property "License" "Apache-2.0")
    (property "MPN" "GRM155R61H104KE14D")
    (property "Manufacturer" "Murata")
    (property "Sheetfile" "ethernet-controller.kicad_sch")
    (property "Sheetname" "Ethernet Controller")
    (property "Val" "100n")
    (property "Voltage" "50V")
    (attr smd)
    (fp_text reference "C11" (at -1.097734 -3.290826 90) (layer "B.SilkS")
      (effects (font (size 0.7 0.7) (thickness 0.15)) (justify left bottom mirror))
    )
    (fp_text value "C_100n_0402" (at 0 -1.4 90) (layer "B.Fab")
      (effects (font (size 0.7 0.7) (thickness 0.15)) (justify left bottom mirror))
    )
    (fp_text user "Author: Antmicro" (at -0.932 -4.17 90) (layer "B.Fab") hide
      (effects (font (size 0.7 0.7) (thickness 0.15)) (justify left bottom mirror))
    )
    (fp_text user "License: Apache-2.0" (at -0.932 -5.17 90) (layer "B.Fab") hide
      (effects (font (size 0.7 0.7) (thickness 0.15)) (justify left bottom mirror))
    )
    (fp_text user "${REFERENCE}" (at -0.932 -3.168 90) (layer "B.Fab") hide
      (effects (font (size 0.7 0.7) (thickness 0.15)) (justify left bottom mirror))
    )
    (fp_rect (start -0.94 0.47) (end 0.94 -0.47) (layer "B.CrtYd") (width 0.05) (fill none))
    (fp_rect (start -0.499 0.249) (end 0.499 -0.249) (layer "B.Fab") (width 0.15) (fill none))
    (pad "1" smd roundrect (at -0.484 0 270) (size 0.59 0.64) (layers "B.Cu" "B.Paste" "B.Mask") (roundrect_rratio 0.25)
      (net 178 "/Ethernet Controller/REG_1V0") (pintype "passive"))
    (pad "2" smd roundrect (at 0.484 0 270) (size 0.59 0.64) (layers "B.Cu" "B.Paste" "B.Mask") (roundrect_rratio 0.25)
      (net 1 "GND") (pintype "passive"))
  )
	(footprint "sa800u-baseboard-hw-footprints:C_0402_1005Metric" (layer "B.Cu")
    (tedit 616D63CF)
    (at 95.249174 106.957733 180)
    (descr "Capacitor SMD 0402")
    (tags "capacitor SMD 0402")
    (property "Author" "Antmicro")
    (property "Dielectric" "X5R")
    (property "License" "Apache-2.0")
    (property "MPN" "GRM155R61H104KE14D")
    (property "Manufacturer" "Murata")
    (property "Sheetfile" "ethernet-controller.kicad_sch")
    (property "Sheetname" "Ethernet Controller")
    (property "Val" "100n")
    (property "Voltage" "50V")
    (attr smd)
    (fp_text reference "C14" (at -1.230826 0.417733) (layer "B.SilkS")
      (effects (font (size 0.7 0.7) (thickness 0.15)) (justify left bottom mirror))
    )
    (fp_text value "C_100n_0402" (at 0 -1.4) (layer "B.Fab")
      (effects (font (size 0.7 0.7) (thickness 0.15)) (justify left bottom mirror))
    )
    (fp_text user "Author: Antmicro" (at -0.932 -4.17) (layer "B.Fab") hide
      (effects (font (size 0.7 0.7) (thickness 0.15)) (justify left bottom mirror))
    )
    (fp_text user "License: Apache-2.0" (at -0.932 -5.17) (layer "B.Fab") hide
      (effects (font (size 0.7 0.7) (thickness 0.15)) (justify left bottom mirror))
    )
    (fp_text user "${REFERENCE}" (at -0.932 -3.168) (layer "B.Fab") hide
      (effects (font (size 0.7 0.7) (thickness 0.15)) (justify left bottom mirror))
    )
    (fp_rect (start -0.94 0.47) (end 0.94 -0.47) (layer "B.CrtYd") (width 0.05) (fill none))
    (fp_rect (start -0.499 0.249) (end 0.499 -0.249) (layer "B.Fab") (width 0.15) (fill none))
    (pad "1" smd roundrect (at -0.484 0 180) (size 0.59 0.64) (layers "B.Cu" "B.Paste" "B.Mask") (roundrect_rratio 0.25)
      (net 181 "/Ethernet Controller/ETH_1V0") (pintype "passive"))
    (pad "2" smd roundrect (at 0.484 0 180) (size 0.59 0.64) (layers "B.Cu" "B.Paste" "B.Mask") (roundrect_rratio 0.25)
      (net 1 "GND") (pintype "passive"))
  )
	(footprint "sa800u-baseboard-hw-footprints:C_0402_1005Metric" (layer "B.Cu")
    (tedit 616D63CF)
    (at 101.549174 106.357734 -90)
    (descr "Capacitor SMD 0402")
    (tags "capacitor SMD 0402")
    (property "Author" "Antmicro")
    (property "DNP" "DNP")
    (property "Dielectric" "")
    (property "License" "Apache-2.0")
    (property "MPN" "C1005X6S1A105K050BC")
    (property "Manufacturer" "TDK")
    (property "Sheetfile" "ethernet-controller.kicad_sch")
    (property "Sheetname" "Ethernet Controller")
    (property "Val" "1u")
    (property "Voltage" "")
    (attr exclude_from_pos_files)
    (fp_text reference "C17" (at -1.117734 -3.160826 90) (layer "B.SilkS")
      (effects (font (size 0.7 0.7) (thickness 0.15)) (justify left bottom mirror))
    )
    (fp_text value "C_1u_0402" (at 0 -1.4 90) (layer "B.Fab")
      (effects (font (size 0.7 0.7) (thickness 0.15)) (justify left bottom mirror))
    )
    (fp_text user "Author: Antmicro" (at -0.932 -4.17 90) (layer "B.Fab") hide
      (effects (font (size 0.7 0.7) (thickness 0.15)) (justify left bottom mirror))
    )
    (fp_text user "${REFERENCE}" (at -0.932 -3.168 90) (layer "B.Fab") hide
      (effects (font (size 0.7 0.7) (thickness 0.15)) (justify left bottom mirror))
    )
    (fp_text user "License: Apache-2.0" (at -0.932 -5.17 90) (layer "B.Fab") hide
      (effects (font (size 0.7 0.7) (thickness 0.15)) (justify left bottom mirror))
    )
    (fp_rect (start -0.94 0.47) (end 0.94 -0.47) (layer "B.CrtYd") (width 0.05) (fill none))
    (fp_rect (start -0.499 0.249) (end 0.499 -0.249) (layer "B.Fab") (width 0.15) (fill none))
    (pad "1" smd roundrect (at -0.484 0 270) (size 0.59 0.64) (layers "B.Cu" "B.Paste" "B.Mask") (roundrect_rratio 0.25)
      (net 181 "/Ethernet Controller/ETH_1V0") (pintype "passive"))
    (pad "2" smd roundrect (at 0.484 0 270) (size 0.59 0.64) (layers "B.Cu" "B.Paste" "B.Mask") (roundrect_rratio 0.25)
      (net 1 "GND") (pintype "passive"))
  )
	(footprint "sa800u-baseboard-hw-footprints:C_0402_1005Metric" (layer "B.Cu")
    (tedit 616D63CF)
    (at 99.691694 109.145244 90)
    (descr "Capacitor SMD 0402")
    (tags "capacitor SMD 0402")
    (property "Author" "Antmicro")
    (property "Dielectric" "C0G")
    (property "License" "Apache-2.0")
    (property "MPN" "GCM1555C1H100GA16D")
    (property "Manufacturer" "Murata")
    (property "Sheetfile" "ethernet-controller.kicad_sch")
    (property "Sheetname" "Ethernet Controller")
    (property "Val" "10p")
    (property "Voltage" "50V")
    (attr smd)
    (fp_text reference "C1" (at 0.675244 1.368306 270) (layer "B.SilkS")
      (effects (font (size 0.7 0.7) (thickness 0.15)) (justify left bottom mirror))
    )
    (fp_text value "C_10p_0402" (at 0 -1.4 270) (layer "B.Fab")
      (effects (font (size 0.7 0.7) (thickness 0.15)) (justify left bottom mirror))
    )
    (fp_text user "${REFERENCE}" (at -0.932 -3.168 270) (layer "B.Fab") hide
      (effects (font (size 0.7 0.7) (thickness 0.15)) (justify left bottom mirror))
    )
    (fp_text user "Author: Antmicro" (at -0.932 -4.17 270) (layer "B.Fab") hide
      (effects (font (size 0.7 0.7) (thickness 0.15)) (justify left bottom mirror))
    )
    (fp_text user "License: Apache-2.0" (at -0.932 -5.17 270) (layer "B.Fab") hide
      (effects (font (size 0.7 0.7) (thickness 0.15)) (justify left bottom mirror))
    )
    (fp_rect (start -0.94 0.47) (end 0.94 -0.47) (layer "B.CrtYd") (width 0.05) (fill none))
    (fp_rect (start -0.499 0.249) (end 0.499 -0.249) (layer "B.Fab") (width 0.15) (fill none))
    (pad "1" smd roundrect (at -0.484 0 90) (size 0.59 0.64) (layers "B.Cu" "B.Paste" "B.Mask") (roundrect_rratio 0.25)
      (net 182 "/Ethernet Controller/XTAL1") (pintype "passive"))
    (pad "2" smd roundrect (at 0.484 0 90) (size 0.59 0.64) (layers "B.Cu" "B.Paste" "B.Mask") (roundrect_rratio 0.25)
      (net 1 "GND") (pintype "passive"))
  )
	(footprint "sa800u-baseboard-hw-footprints:C_0402_1005Metric" (layer "B.Cu")
    (tedit 616D63CF)
    (at 94.459104 109.145243 -90)
    (descr "Capacitor SMD 0402")
    (tags "capacitor SMD 0402")
    (property "Author" "Antmicro")
    (property "Dielectric" "C0G")
    (property "License" "Apache-2.0")
    (property "MPN" "GCM1555C1H100GA16D")
    (property "Manufacturer" "Murata")
    (property "Sheetfile" "ethernet-controller.kicad_sch")
    (property "Sheetname" "Ethernet Controller")
    (property "Val" "10p")
    (property "Voltage" "50V")
    (attr smd)
    (fp_text reference "C2" (at 0.914757 -0.320896 90) (layer "B.SilkS")
      (effects (font (size 0.7 0.7) (thickness 0.15)) (justify left bottom mirror))
    )
    (fp_text value "C_10p_0402" (at 0 -1.4 90) (layer "B.Fab")
      (effects (font (size 0.7 0.7) (thickness 0.15)) (justify left bottom mirror))
    )
    (fp_text user "License: Apache-2.0" (at -0.932 -5.17 90) (layer "B.Fab") hide
      (effects (font (size 0.7 0.7) (thickness 0.15)) (justify left bottom mirror))
    )
    (fp_text user "${REFERENCE}" (at -0.932 -3.168 90) (layer "B.Fab") hide
      (effects (font (size 0.7 0.7) (thickness 0.15)) (justify left bottom mirror))
    )
    (fp_text user "Author: Antmicro" (at -0.932 -4.17 90) (layer "B.Fab") hide
      (effects (font (size 0.7 0.7) (thickness 0.15)) (justify left bottom mirror))
    )
    (fp_rect (start -0.94 0.47) (end 0.94 -0.47) (layer "B.CrtYd") (width 0.05) (fill none))
    (fp_rect (start -0.499 0.249) (end 0.499 -0.249) (layer "B.Fab") (width 0.15) (fill none))
    (pad "1" smd roundrect (at -0.484 0 270) (size 0.59 0.64) (layers "B.Cu" "B.Paste" "B.Mask") (roundrect_rratio 0.25)
      (net 183 "/Ethernet Controller/XTAL2") (pintype "passive"))
    (pad "2" smd roundrect (at 0.484 0 270) (size 0.59 0.64) (layers "B.Cu" "B.Paste" "B.Mask") (roundrect_rratio 0.25)
      (net 1 "GND") (pintype "passive"))
  )
	(footprint "sa800u-baseboard-hw-footprints:R_0402_1005Metric" (layer "B.Cu")
    (tedit 5FD9C158)
    (at 100.549174 106.357734 90)
    (descr "Resistor SMD 0402")
    (tags "resistor SMD 0402")
    (property "Author" "Antmicro")
    (property "Current" "1A")
    (property "License" "Apache-2.0")
    (property "MPN" "ERJ2GE0R00X")
    (property "Manufacturer" "Panasonic")
    (property "Sheetfile" "ethernet-controller.kicad_sch")
    (property "Sheetname" "Ethernet Controller")
    (property "Tolerance" "")
    (property "Val" "0R")
    (attr smd)
    (fp_text reference "R12" (at 1.107734 3.220826 270) (layer "B.SilkS")
      (effects (font (size 0.7 0.7) (thickness 0.15)) (justify left bottom mirror))
    )
    (fp_text value "R_0R_0402" (at 0 -1.4 270) (layer "B.Fab")
      (effects (font (size 0.7 0.7) (thickness 0.15)) (justify left bottom mirror))
    )
    (fp_text user "${REFERENCE}" (at -0.95 -3.168 270) (layer "B.Fab") hide
      (effects (font (size 0.7 0.7) (thickness 0.15)) (justify left bottom mirror))
    )
    (fp_text user "License: Apache-2.0" (at -0.95 -5.169 270) (layer "B.Fab") hide
      (effects (font (size 0.7 0.7) (thickness 0.15)) (justify left bottom mirror))
    )
    (fp_text user "Author: Antmicro" (at -0.95 -4.169 270) (layer "B.Fab") hide
      (effects (font (size 0.7 0.7) (thickness 0.15)) (justify left bottom mirror))
    )
    (fp_rect (start -0.93 0.47) (end 0.93 -0.47) (layer "B.CrtYd") (width 0.05) (fill none))
    (fp_rect (start -0.5 0.25) (end 0.5 -0.25) (layer "B.Fab") (width 0.15) (fill none))
    (pad "1" smd roundrect (at -0.485 0 90) (size 0.59 0.64) (layers "B.Cu" "B.Paste" "B.Mask") (roundrect_rratio 0.25)
      (net 178 "/Ethernet Controller/REG_1V0") (pintype "passive"))
    (pad "2" smd roundrect (at 0.485 0 90) (size 0.59 0.64) (layers "B.Cu" "B.Paste" "B.Mask") (roundrect_rratio 0.25)
      (net 181 "/Ethernet Controller/ETH_1V0") (pintype "passive"))
  )
	(footprint "sa800u-baseboard-hw-footprints:R_0402_1005Metric" (layer "B.Cu")
    (tedit 5FD9C158)
    (at 97.149174 106.957733)
    (descr "Resistor SMD 0402")
    (tags "resistor SMD 0402")
    (property "Author" "Antmicro")
    (property "DNP" "DNP")
    (property "License" "Apache-2.0")
    (property "MPN" "CR0402-FX-1004GLF")
    (property "Manufacturer" "Bourns")
    (property "Sheetfile" "ethernet-controller.kicad_sch")
    (property "Sheetname" "Ethernet Controller")
    (property "Tolerance" "1%")
    (property "Val" "1M")
    (attr exclude_from_pos_files)
    (fp_text reference "R5" (at 0.670826 -0.447733 180) (layer "B.SilkS")
      (effects (font (size 0.7 0.7) (thickness 0.15)) (justify left bottom mirror))
    )
    (fp_text value "R_1M_0402" (at 0 -1.4 180) (layer "B.Fab")
      (effects (font (size 0.7 0.7) (thickness 0.15)) (justify left bottom mirror))
    )
    (fp_text user "Author: Antmicro" (at -0.95 -4.169 180) (layer "B.Fab") hide
      (effects (font (size 0.7 0.7) (thickness 0.15)) (justify left bottom mirror))
    )
    (fp_text user "${REFERENCE}" (at -0.95 -3.168 180) (layer "B.Fab") hide
      (effects (font (size 0.7 0.7) (thickness 0.15)) (justify left bottom mirror))
    )
    (fp_text user "License: Apache-2.0" (at -0.95 -5.169 180) (layer "B.Fab") hide
      (effects (font (size 0.7 0.7) (thickness 0.15)) (justify left bottom mirror))
    )
    (fp_rect (start -0.93 0.47) (end 0.93 -0.47) (layer "B.CrtYd") (width 0.05) (fill none))
    (fp_rect (start -0.5 0.25) (end 0.5 -0.25) (layer "B.Fab") (width 0.15) (fill none))
    (pad "1" smd roundrect (at -0.485 0) (size 0.59 0.64) (layers "B.Cu" "B.Paste" "B.Mask") (roundrect_rratio 0.25)
      (net 183 "/Ethernet Controller/XTAL2") (pintype "passive"))
    (pad "2" smd roundrect (at 0.485 0) (size 0.59 0.64) (layers "B.Cu" "B.Paste" "B.Mask") (roundrect_rratio 0.25)
      (net 182 "/Ethernet Controller/XTAL1") (pintype "passive"))
  )
	(footprint "sa800u-baseboard-hw-footprints:Oscillator_SMD_Geyer_KX-7-4Pin_3.2x2.5mm" (layer "B.Cu")
    (tedit 5D7218CB)
    (at 97.14611 109.145244 180)
    (property "Author" "Antmicro")
    (property "License" "Apache-2.0")
    (property "MPN" "ABM8G-25.000MHZ-18-D2Y-T")
    (property "Manufacturer" "Abracon")
    (property "Sheetfile" "ethernet-controller.kicad_sch")
    (property "Sheetname" "Ethernet Controller")
    (property "Val" "25MHz")
    (attr smd)
    (fp_text reference "Y1" (at 0.84611 -2.524756) (layer "B.SilkS")
      (effects (font (size 0.7 0.7) (thickness 0.15)) (justify right bottom mirror))
    )
    (fp_text value "Oscillator_SMD_25MHz_KX-7" (at -1.75 -2.548) (layer "B.Fab")
      (effects (font (size 0.7 0.7) (thickness 0.15)) (justify left bottom mirror))
    )
    (fp_text user "License: Apache-2.0" (at -1.75 -6.5) (layer "B.Fab") hide
      (effects (font (size 0.7 0.7) (thickness 0.15)) (justify left bottom mirror))
    )
    (fp_text user "Author: Antmicro" (at -1.75 -5) (layer "B.Fab") hide
      (effects (font (size 0.7 0.7) (thickness 0.15)) (justify left bottom mirror))
    )
    (fp_text user "${REFERENCE}" (at -1.75 -3.75) (layer "B.Fab") hide
      (effects (font (size 0.7 0.7) (thickness 0.15)) (justify left bottom mirror))
    )
    (fp_line (start 1.6 -0.3) (end 1.6 0.2) (layer "B.SilkS") (width 0.15))
    (fp_line (start -0.35 1.25) (end 0.45 1.25) (layer "B.SilkS") (width 0.15))
    (fp_line (start -1.6 -0.3) (end -1.6 0.2) (layer "B.SilkS") (width 0.15))
    (fp_line (start -0.35 -1.25) (end 0.45 -1.25) (layer "B.SilkS") (width 0.15))
    (fp_circle (center -1.75 -1.5) (end -1.7 -1.5) (layer "B.SilkS") (width 0.15) (fill none))
    (fp_rect (start -1.907 1.55) (end 2.006 -1.649) (layer "B.CrtYd") (width 0.05) (fill none))
    (pad "1" smd roundrect (at -1.101 -0.949 180) (size 1.3 1.1) (layers "B.Cu" "B.Paste" "B.Mask") (roundrect_rratio 0)
      (chamfer_ratio 0.2) (chamfer top_left)
      (net 182 "/Ethernet Controller/XTAL1") (pintype "passive"))
    (pad "2" smd rect (at 1.199 -0.949 180) (size 1.3 1.1) (layers "B.Cu" "B.Paste" "B.Mask")
      (net 1 "GND") (pinfunction "SH") (pintype "passive"))
    (pad "3" smd rect (at 1.199 0.85 180) (size 1.3 1.1) (layers "B.Cu" "B.Paste" "B.Mask")
      (net 183 "/Ethernet Controller/XTAL2") (pintype "passive"))
    (pad "4" smd rect (at -1.101 0.85 180) (size 1.3 1.1) (layers "B.Cu" "B.Paste" "B.Mask")
      (net 1 "GND") (pinfunction "SH") (pintype "passive"))
  )
	(footprint "sa800u-baseboard-hw-footprints:C_0402_1005Metric" (layer "B.Cu")
    (tedit 616D63CF)
    (at 101.549174 104.257734)
    (descr "Capacitor SMD 0402")
    (tags "capacitor SMD 0402")
    (property "Author" "Antmicro")
    (property "Dielectric" "X5R")
    (property "License" "Apache-2.0")
    (property "MPN" "GRM155R61H104KE14D")
    (property "Manufacturer" "Murata")
    (property "Sheetfile" "ethernet-controller.kicad_sch")
    (property "Sheetname" "Ethernet Controller")
    (property "Val" "100n")
    (property "Voltage" "50V")
    (attr smd)
    (fp_text reference "C4" (at 2.410826 0.282266 180) (layer "B.SilkS")
      (effects (font (size 0.7 0.7) (thickness 0.15)) (justify left bottom mirror))
    )
    (fp_text value "C_100n_0402" (at 0 -1.4 180) (layer "B.Fab")
      (effects (font (size 0.7 0.7) (thickness 0.15)) (justify left bottom mirror))
    )
    (fp_text user "${REFERENCE}" (at -0.932 -3.168 180) (layer "B.Fab") hide
      (effects (font (size 0.7 0.7) (thickness 0.15)) (justify left bottom mirror))
    )
    (fp_text user "Author: Antmicro" (at -0.932 -4.17 180) (layer "B.Fab") hide
      (effects (font (size 0.7 0.7) (thickness 0.15)) (justify left bottom mirror))
    )
    (fp_text user "License: Apache-2.0" (at -0.932 -5.17 180) (layer "B.Fab") hide
      (effects (font (size 0.7 0.7) (thickness 0.15)) (justify left bottom mirror))
    )
    (fp_rect (start -0.94 0.47) (end 0.94 -0.47) (layer "B.CrtYd") (width 0.05) (fill none))
    (fp_rect (start -0.499 0.249) (end 0.499 -0.249) (layer "B.Fab") (width 0.15) (fill none))
    (pad "1" smd roundrect (at -0.484 0) (size 0.59 0.64) (layers "B.Cu" "B.Paste" "B.Mask") (roundrect_rratio 0.25)
      (net 177 "/Ethernet Controller/ETH_3V3") (pintype "passive"))
    (pad "2" smd roundrect (at 0.484 0) (size 0.59 0.64) (layers "B.Cu" "B.Paste" "B.Mask") (roundrect_rratio 0.25)
      (net 1 "GND") (pintype "passive"))
  )
)
